FILE_TYPE = CONNECTIVITY;
{Allegro Design Entry HDL 17.4-2019 S026 (4007227) 1/17/2022}
"PAGE_NUMBER" = 337;
0"NC";
1"GND\g";
2"GND\g";
3"GND\g";
4"GND\g";
5"P3V3_AUX\g";
6"GND\g";
7"GND\g";
8"P3V3_AUX\g";
9"GND\g";
10"GND\g";
11"GND\g";
12"P3V3_AUX\g";
13"GND\g";
14"GND\g";
15"GND\g";
16"CLK_50M_NCSI_OCP_SFF_ISO"CDS_PHYS_NET_NAME"CLK_50M_NCSI_OCP_SFF_ISO";
17"CLK_50M_NCSI_OCP_SFF_ISO_R"CDS_PHYS_NET_NAME"CLK_50M_NCSI_OCP_SFF_ISO_R";
18"CLK_50M_RMII_BMC_OCP"CDS_PHYS_NET_NAME"CLK_50M_RMII_BMC_OCP";
19"IRQ_LVC3_WAKE_BUF_N"CDS_PHYS_NET_NAME"IRQ_LVC3_WAKE_BUF_N";
20"RST_PERST_OCP_SFF_BUF2_N";
21"PU_OCP_SFF_WAKE_OE"CDS_PHYS_NET_NAME"PU_OCP_SFF_WAKE_OE";
22"P3V3_AUX\g";
23"RST_PERST_OCP_SFF_BUF_N"CDS_PHYS_NET_NAME"RST_HP_OCP_V3_1_N";
24"RST_PERST0_OCP_SFF_N";
25"RST_PERST1_OCP_SFF_N";
26"RST_PERST2_OCP_SFF_N";
27"RST_PERST3_OCP_SFF_N";
28"CLK_50M_NCSI_OCP_V3_2"CDS_PHYS_NET_NAME"CLK_50M_NCSI_OCP_V3_2";
29"NC_U157_NC1"CDS_PHYS_NET_NAME"NC_U157_NC1";
30"P3V3_AUX\g";
31"OCP_SFF_PWRBRK_BUFF_N"CDS_PHYS_NET_NAME"OCP_SFF_PWRBRK_BUFF_N";
32"IRQ_OCP_SFF_WAKE_BUF_N"CDS_PHYS_NET_NAME"IRQ_LVC3_WAKE_N";
33"CLK_50M_NCSI_OCP_SFF"CDS_PHYS_NET_NAME"CLK_50M_NCSI_OCP_SFF";
34"FB_BMC_ISOLATE";
35"P3V3_AUX\g";
36"GND\g";
37"P3V3_AUX\g";
38"P3V3_AUX\g"$PHYS_NET_NAME"P3V3_AUX"CDS_PHYS_NET_NAME"P3V3_AUX"VOLTAGE"3.3";
39"P3V3_AUX\g";
40"P3V3_AUX\g";
41"GND\g";
42"CLK_50M_NCSI_OCP_SFF"CDS_PHYS_NET_NAME"CLK_50M_NCSI_OCP_SFF";
43"CLK_50M_NCSI_OCP_2"CDS_PHYS_NET_NAME"CLK_50M_NCSI_OCP_2";
44"TP_CLK_50M_Y3"CDS_PHYS_NET_NAME"TP_CLK_50M_PCH_LOM";
45"CLK_50M_NCSI_OCP_1"CDS_PHYS_NET_NAME"CLK_50M_NCSI_OCP_1";
46"OCP_SFF_PWRBRK_N"CDS_PHYS_NET_NAME"OCP_SFF_PWRBRK_N";
47"OCP_SFF_WAKE_BUFF_R_N"CDS_PHYS_NET_NAME"OCP_SFF_WAKE_BUFF_R_N";
48"OCP_SFF_WAKE_BUFF_N"CDS_PHYS_NET_NAME"OCP_SFF_WAKE_BUFF_N";
49"CLK_50M_BMC_MAC_R"CDS_PHYS_NET_NAME"CLK_50M_BMC_MAC_R";
50"CLK_50M_EN";
51"CLK_50M_RMII_R";
52"FM_SYS_THROTTLE_N"CDS_PHYS_NET_NAME"FM_SYS_THROTTLE_N";
53"NC_U104_NC1"CDS_PHYS_NET_NAME"NC_U104_NC1";
54"P3V3_OCP_SFF\g";
55"IRQ_LVC3_OCP_SFF_WAKE_N"CDS_PHYS_NET_NAME"IRQ_LVC3_OCP_SFF_WAKE_N";
56"CLK_50M_RMII";
%"Q_RES"
"2","(-10225,2725)","2","pure_quanta","I1";
;
LOCATION"R1138"
$SEC"1"
CDS_SEC"1"
WATTAGE"1/16W"
TOLERANCE"1%"
VALUE"10K"
MATERIAL"CHIP"
PACK_TYPE"0402LF"
CDS_LIB"pure_quanta"
PART_NUMBER"CS31002FB08";
"A"
$PN"1"40;
"B"
$PN"2"50;
%"Q_RES"
"2","(-9675,4625)","2","pure_quanta","I11";
;
LOCATION"R1824"
$SEC"1"
CDS_SEC"1"
MATERIAL"CHIP"
WATTAGE"1/16W"
TOLERANCE"1%"
PACK_TYPE"0402LF"
VALUE"10K"
CDS_LIB"pure_quanta"
PART_NUMBER"CS31002FB08";
"A"
$PN"1"54;
"B"
$PN"2"55;
%"Q_RES"
"2","(-9400,4625)","0","pure_quanta","I12";
;
LOCATION"R45"
$SEC"1"
CDS_SEC"1"
TOLERANCE"1%"
VALUE"10K"
MATERIAL"CHIP"
WATTAGE"1/16W"
PACK_TYPE"0402LF"
CDS_LIB"pure_quanta"
PART_NUMBER"CS31002FB08";
"A"
$PN"1"54;
"B"
$PN"2"21;
%"UNIVERSAL_POWER"
"1","(-9400,4975)","0","pure_quanta_power","I13";
;
HDL_POWER"P3V3_OCP_SFF"
CDS_LIB"pure_quanta_power";
"A"54;
%"UNIVERSAL_GND"
"1","(-6550,2150)","0","pure_quanta_power","I15";
;
ROOM"IO_SLOT"
CDS_LIB"pure_quanta_power"
HDL_POWER"GND";
"A"36;
%"PI6CV304LE"
"1","(-6975,2450)","0","pure_quanta","I16";
;
LOCATION"U90"
$SEC"1"
CDS_SEC"1"
MATERIAL"IC"
VALUE"PI6CV304LE"
PART_TYPE"SMLF"
CDS_LMAN_SYM_OUTLINE"-150,225,150,-225"
CDS_LIB"pure_quanta"
PART_NUMBER"AL000304K01";
"GND"
$PN"4"36;
"VDD"
$PN"6"37;
"Y3"
$PN"8"44;
"Y2"
$PN"7"43;
"Y1"
$PN"5"45;
"Y0"
$PN"3"49;
"OE"
$PN"2"50;
"CLK_IN"
$PN"1"51;
%"UNIVERSAL_POWER"
"1","(-6475,3175)","0","pure_quanta_power","I17";
;
HDL_POWER"P3V3_AUX"
CDS_LIB"pure_quanta_power";
"A"37;
%"UNIVERSAL_GND"
"1","(-6250,2625)","0","pure_quanta_power","I18";
;
CDS_LIB"pure_quanta_power"
HDL_POWER"GND";
"A"1;
%"Q_CAP"
"1","(-6250,2850)","0","pure_quanta","I19";
;
LOCATION"C1275"
$SEC"1"
CDS_SEC"1"
VOLTAGE"25V"
MATERIAL"X7R"
VALUE"0.1UF"
TOLERANCE"10%"
PACK_TYPE"0402"
CDS_LIB"pure_quanta"
PART_NUMBER"CH4104K1B00";
"B"
$PN"2"1;
"A"
$PN"1"37;
%"UNIVERSAL_GND"
"1","(-9875,2525)","0","pure_quanta_power","I2";
;
ROOM"IO_SLOT"
CDS_LIB"pure_quanta_power"
HDL_POWER"GND";
"A"2;
%"Q_RES"
"1","(-5550,2425)","0","pure_quanta","I20";
;
LOCATION"R3181"
$SEC"1"
CDS_SEC"1"
MATERIAL"CHIP"
VALUE"27.4"
TOLERANCE"1%"
WATTAGE"1/16W"
CDS_LIB"pure_quanta"
PACK_TYPE"0402LF"
PART_NUMBER"CS02742FB03";
"B"
$PN"2"28;
"A"
$PN"1"43;
%"Q_RES"
"1","(-5550,2475)","0","pure_quanta","I21";
;
LOCATION"R1141"
$SEC"1"
CDS_SEC"1"
VALUE"27.4"
MATERIAL"CHIP"
TOLERANCE"1%"
PACK_TYPE"0402LF"
CDS_LIB"pure_quanta"
WATTAGE"1/16W"
PART_NUMBER"CS02742FB03";
"B"
$PN"2"42;
"A"
$PN"1"45;
%"Q_RES"
"1","(-5550,2525)","0","pure_quanta","I22";
;
LOCATION"R1140"
$SEC"1"
CDS_SEC"1"
TOLERANCE"1%"
VALUE"27.4"
WATTAGE"1/16W"
MATERIAL"CHIP"
PACK_TYPE"0402LF"
CDS_LIB"pure_quanta"
PART_NUMBER"CS02742FB03";
"B"
$PN"2"18;
"A"
$PN"1"49;
%"UNIVERSAL_GND"
"1","(-5425,3925)","0","pure_quanta_power","I24";
;
CDS_LIB"pure_quanta_power"
HDL_POWER"GND";
"A"3;
%"74LVC1G07GV"
"1","(-4950,4250)","0","pure_quanta","I25";
;
LOCATION"U157"
$SEC"1"
CDS_SEC"1"
VALUE"74LVC1G07GV"
PART_TYPE"SMLF"
MATERIAL"IC"
CDS_LIB"pure_quanta"
CDS_LMAN_SYM_OUTLINE"-125,150,125,-150"
NEEDS_NO_SIZE"TRUE"
PART_NUMBER"AL1G0007001";
"NC1"
$PN"1"29;
"Y"
$PN"4"19;
"GND"
$PN"3"3;
"A"
$PN"2"47;
"VCC"
$PN"5"39;
%"Q_RES"
"1","(-4625,3275)","0","pure_quanta","I29";
;
LOCATION"R4601"
$SEC"1"
CDS_SEC"1"
VALUE"0"
MATERIAL"CHIP"
CDS_LIB"pure_quanta"
PACK_TYPE"0402LF"
TOLERANCE"5%"
WATTAGE"1/16W"
PART_NUMBER"CS00002JB13";
"B"
$PN"2"17;
"A"
$PN"1"16;
%"Q_CAP"
"1","(-9875,2750)","2","pure_quanta","I3";
;
LOCATION"C1274"
$SEC"1"
CDS_SEC"1"
TOLERANCE"10%"
VALUE"0.1UF"
VOLTAGE"25V"
MATERIAL"X7R"
PACK_TYPE"0402"
CDS_LIB"pure_quanta"
PART_NUMBER"CH4104K1B00";
"B"
$PN"2"2;
"A"
$PN"1"40;
%"Q_RES"
"1","(-6725,4250)","0","pure_quanta","I31";
;
LOCATION"R1594"
$SEC"1"
CDS_SEC"1"
WATTAGE"1/16W"
PACK_TYPE"0402LF"
VALUE"33.2"
TOLERANCE"1%"
MATERIAL"CHIP"
CDS_LIB"pure_quanta"
PART_NUMBER"CS03322FB03";
"B"
$PN"2"47;
"A"
$PN"1"48;
%"UNIVERSAL_GND"
"1","(-7900,4575)","0","pure_quanta_power","I32";
;
CDS_LIB"pure_quanta_power"
HDL_POWER"GND";
"A"4;
%"Q_CAP"
"1","(-7900,4800)","0","pure_quanta","I33";
;
LOCATION"C36"
$SEC"1"
CDS_SEC"1"
VALUE"0.1UF"
TOLERANCE"10%"
MATERIAL"X7R"
PACK_TYPE"0402"
VOLTAGE"25V"
CDS_LIB"pure_quanta"
PART_NUMBER"CH4104K1B00";
"B"
$PN"2"4;
"A"
$PN"1"38;
%"UNIVERSAL_POWER"
"1","(-7900,5150)","0","pure_quanta_power","I34";
;
HDL_POWER"P3V3_AUX"
CDS_LIB"pure_quanta_power";
"A"38;
%"Q_RES"
"2","(-7050,4700)","0","pure_quanta","I35";
;
LOCATION"R2488"
$SEC"1"
CDS_SEC"1"
WATTAGE"1/16W"
MATERIAL"CHIP"
PACK_TYPE"0402LF"
TOLERANCE"1%"
VALUE"4.7K"
CDS_LIB"pure_quanta"
PART_NUMBER"CS24702FB06";
"A"
$PN"1"5;
"B"
$PN"2"48;
%"UNIVERSAL_POWER"
"1","(-7050,4900)","0","pure_quanta_power","I36";
;
HDL_POWER"P3V3_AUX"
CDS_LIB"pure_quanta_power";
"A"5;
%"UNIVERSAL_GND"
"1","(-7725,5500)","0","pure_quanta_power","I37";
;
CDS_LIB"pure_quanta_power"
HDL_POWER"GND";
"A"6;
%"74LVC1G07GV"
"1","(-7250,5825)","0","pure_quanta","I38";
;
LOCATION"U104"
$SEC"1"
CDS_SEC"1"
VALUE"74LVC1G07GV"
PART_TYPE"SMLF"
MATERIAL"IC"
CDS_LMAN_SYM_OUTLINE"-125,150,125,-150"
NEEDS_NO_SIZE"TRUE"
CDS_LIB"pure_quanta"
PART_NUMBER"AL1G0007001";
"NC1"
$PN"1"53;
"Y"
$PN"4"31;
"GND"
$PN"3"6;
"A"
$PN"2"52;
"VCC"
$PN"5"30;
%"UNIVERSAL_GND"
"1","(-6575,5975)","0","pure_quanta_power","I39";
;
CDS_LIB"pure_quanta_power"
HDL_POWER"GND";
"A"7;
%"Q_OSC4P"
"1","(-9275,2450)","0","pure_quanta","I4";
;
LOCATION"OSC1"
$SEC"1"
CDS_SEC"1"
PACK_TYPE"SMLF"
VALUE"50MHZ"
MATERIAL"OSC"
CDS_LIB"pure_quanta"
NEEDS_NO_SIZE"TRUE"
PART_NUMBER"BF650000032";
"VDD"
$PN"4"40;
"OUT"
$PN"3"56;
"GND"
$PN"2"41;
"OE"
$PN"1"50;
%"Q_CAP"
"1","(-6575,6200)","0","pure_quanta","I40";
;
LOCATION"C72"
$SEC"1"
CDS_SEC"1"
PACK_TYPE"0402"
MATERIAL"X7R"
TOLERANCE"10%"
VOLTAGE"25V"
VALUE"0.1UF"
CDS_LIB"pure_quanta"
PART_NUMBER"CH4104K1B00";
"B"
$PN"2"7;
"A"
$PN"1"30;
%"UNIVERSAL_POWER"
"1","(-6775,6475)","0","pure_quanta_power","I41";
;
HDL_POWER"P3V3_AUX"
CDS_LIB"pure_quanta_power";
"A"30;
%"Q_RES"
"2","(-5875,6100)","0","pure_quanta","I42";
;
LOCATION"R53"
$SEC"1"
CDS_SEC"1"
TOLERANCE"1%"
PACK_TYPE"0402LF"
MATERIAL"CHIP"
VALUE"4.7K"
WATTAGE"1/16W"
CDS_LIB"pure_quanta"
PART_NUMBER"CS24702FB06";
"A"
$PN"1"8;
"B"
$PN"2"31;
%"UNIVERSAL_POWER"
"1","(-5875,6300)","0","pure_quanta_power","I43";
;
HDL_POWER"P3V3_AUX"
CDS_LIB"pure_quanta_power";
"A"8;
%"Q_RES"
"1","(-5325,5725)","0","pure_quanta","I44";
;
LOCATION"R1595"
$SEC"1"
CDS_SEC"1"
TOLERANCE"1%"
WATTAGE"1/16W"
PACK_TYPE"0402LF"
VALUE"33.2"
MATERIAL"CHIP"
CDS_LIB"pure_quanta"
PART_NUMBER"CS03322FB03";
"B"
$PN"2"46;
"A"
$PN"1"31;
%"UNIVERSAL_POWER"
"1","(-4525,4800)","0","pure_quanta_power","I45";
;
HDL_POWER"P3V3_AUX"
CDS_LIB"pure_quanta_power";
"A"39;
%"UNIVERSAL_GND"
"1","(-4325,4300)","0","pure_quanta_power","I46";
;
CDS_LIB"pure_quanta_power"
HDL_POWER"GND";
"A"9;
%"Q_CAP"
"1","(-4325,4525)","0","pure_quanta","I47";
;
LOCATION"C1663"
$SEC"1"
CDS_SEC"1"
TOLERANCE"10%"
VALUE"0.1UF"
VOLTAGE"25V"
MATERIAL"X7R"
PACK_TYPE"0402"
CDS_LIB"pure_quanta"
PART_NUMBER"CH4104K1B00";
"B"
$PN"2"9;
"A"
$PN"1"39;
%"UNIVERSAL_GND"
"1","(-3600,3025)","0","pure_quanta_power","I49";
;
CDS_LIB"pure_quanta_power"
HDL_POWER"GND";
"A"10;
%"UNIVERSAL_POWER"
"1","(-9775,3125)","0","pure_quanta_power","I5";
;
HDL_POWER"P3V3_AUX"
CDS_LIB"pure_quanta_power";
"A"40;
%"Q_RES"
"1","(-3475,4150)","0","pure_quanta","I50";
;
LOCATION"R2489"
$SEC"1"
CDS_SEC"1"
MATERIAL"CHIP"
VALUE"33.2"
WATTAGE"1/16W"
TOLERANCE"1%"
PACK_TYPE"0402LF"
CDS_LIB"pure_quanta"
PART_NUMBER"CS03322FB03";
"B"
$PN"2"32;
"A"
$PN"1"19;
%"UNIVERSAL_GND"
"1","(-2525,3325)","0","pure_quanta_power","I52";
;
CDS_LIB"pure_quanta_power"
HDL_POWER"GND";
"A"11;
%"Q_CAP"
"1","(-2525,3550)","0","pure_quanta","I53";
;
LOCATION"C2344"
$SEC"1"
CDS_SEC"1"
PACK_TYPE"0402"
VOLTAGE"25V"
TOLERANCE"10%"
VALUE"0.1UF"
MATERIAL"X7R"
CDS_LIB"pure_quanta"
PART_NUMBER"CH4104K1B00";
"B"
$PN"2"11;
"A"
$PN"1"35;
%"UNIVERSAL_POWER"
"1","(-2725,3825)","0","pure_quanta_power","I54";
;
HDL_POWER"P3V3_AUX"
CDS_LIB"pure_quanta_power";
"A"35;
%"Q_RES"
"2","(-3775,4600)","0","pure_quanta","I56";
;
LOCATION"R2487"
$SEC"1"
CDS_SEC"1"
MATERIAL"EMPTY"
PACK_TYPE"0402LF"
TOLERANCE"1%"
WATTAGE"1/16W"
VALUE"4.7K"
CDS_LIB"pure_quanta"
PART_NUMBER"CS24702FB06";
"A"
$PN"1"12;
"B"
$PN"2"19;
%"UNIVERSAL_POWER"
"1","(-3775,4800)","0","pure_quanta_power","I57";
;
HDL_POWER"P3V3_AUX"
CDS_LIB"pure_quanta_power";
"A"12;
%"UNIVERSAL_GND"
"1","(-8825,2250)","0","pure_quanta_power","I6";
;
ROOM"IO_SLOT"
CDS_LIB"pure_quanta_power"
HDL_POWER"GND";
"A"41;
%"UNIVERSAL_GND"
"1","(-8475,7125)","0","pure_quanta_power","I60";
;
CDS_LIB"pure_quanta_power"
HDL_POWER"GND";
"A"13;
%"Q_CAP"
"1","(-8475,7350)","2","pure_quanta","I61";
;
LOCATION"C10"
$SEC"1"
CDS_SEC"1"
TOLERANCE"10%"
VOLTAGE"25V"
PACK_TYPE"0402"
VALUE"0.1UF"
MATERIAL"X7R"
CDS_LIB"pure_quanta"
PART_NUMBER"CH4104K1B00";
"B"
$PN"2"13;
"A"
$PN"1"22;
%"UNIVERSAL_GND"
"1","(-8150,6775)","0","pure_quanta_power","I62";
;
CDS_LIB"pure_quanta_power"
HDL_POWER"GND";
"A"14;
%"UNIVERSAL_POWER"
"1","(-8275,7625)","0","pure_quanta_power","I63";
;
HDL_POWER"P3V3_AUX"
CDS_LIB"pure_quanta_power";
"A"22;
%"74LVC1G17GW"
"1","(-7975,7025)","0","pure_quanta","I64";
;
LOCATION"U75"
SEC"1"
VALUE"74LVC1G17GW"
MATERIAL"IC"
PART_TYPE"SMLF"
PIN_NAMES_ROTATE"True"
CDS_LMAN_SYM_OUTLINE"-125,150,125,-150"
CDS_LIB"pure_quanta"
SEC_TYPE""
PART_NUMBER"AL1G0017K01";
"NC"
$PN"1"0;
"Y"
$PN"4"20;
"GND"
$PN"3"14;
"A"
$PN"2"23;
"VCC"
$PN"5"22;
%"Q_RES"
"1","(-8150,2525)","0","pure_quanta","I7";
;
LOCATION"R1139"
$SEC"1"
CDS_SEC"1"
WATTAGE"1/16W"
PACK_TYPE"0402LF"
MATERIAL"CHIP"
VALUE"0"
TOLERANCE"5%"
CDS_LIB"pure_quanta"
PART_NUMBER"CS00002JB13";
"B"
$PN"2"51;
"A"
$PN"1"56;
%"Q_RES"
"1","(-6975,6975)","0","pure_quanta","I78";
;
LOCATION"R899"
$SEC"1"
CDS_SEC"1"
VALUE"0"
CDS_LIB"pure_quanta"
BOM_COST"MEM"
WATTAGE"1/16W"
MATERIAL"CHIP"
TOLERANCE"5%"
PACK_TYPE"0402LF"
PART_NUMBER"CS00002JB13";
"B"
$PN"2"25;
"A"
$PN"1"20;
%"Q_RES"
"1","(-6975,7025)","0","pure_quanta","I79";
;
LOCATION"R877"
$SEC"1"
CDS_SEC"1"
VALUE"0"
PACK_TYPE"0402LF"
TOLERANCE"5%"
MATERIAL"CHIP"
WATTAGE"1/16W"
BOM_COST"MEM"
CDS_LIB"pure_quanta"
PART_NUMBER"CS00002JB13";
"B"
$PN"2"24;
"A"
$PN"1"20;
%"74LVC1G126SE7"
"1","(-8175,4250)","0","pure_quanta","I8";
;
LOCATION"U8082"
$SEC"1"
CDS_SEC"1"
VALUE"74LVC1G126SE-7"
PART_TYPE"SMLF"
MATERIAL"IC"
NEEDS_NO_SIZE"TRUE"
CDS_LMAN_SYM_OUTLINE"-100,100,100,-100"
CDS_LIB"pure_quanta"
PART_NUMBER"AL1G0126009";
"OE"
$PN"1"21;
"GND"
$PN"3"15;
"VCC"
$PN"5"38;
"Y"
$PN"4"48;
"A"
$PN"2"55;
%"Q_RES"
"1","(-6975,6925)","0","pure_quanta","I80";
;
LOCATION"R905"
$SEC"1"
CDS_SEC"1"
VALUE"0"
CDS_LIB"pure_quanta"
BOM_COST"MEM"
WATTAGE"1/16W"
MATERIAL"CHIP"
TOLERANCE"5%"
PACK_TYPE"0402LF"
PART_NUMBER"CS00002JB13";
"B"
$PN"2"26;
"A"
$PN"1"20;
%"Q_RES"
"1","(-6975,6875)","0","pure_quanta","I81";
;
LOCATION"R956"
$SEC"1"
CDS_SEC"1"
VALUE"0"
CDS_LIB"pure_quanta"
BOM_COST"MEM"
WATTAGE"1/16W"
MATERIAL"CHIP"
TOLERANCE"5%"
PACK_TYPE"0402LF"
PART_NUMBER"CS00002JB13";
"B"
$PN"2"27;
"A"
$PN"1"20;
%"74LVC1G66GV"
"1","(-3175,3275)","0","pure_quanta","I82";
;
LOCATION"U320"
SEC"1"
VALUE"74LVC1G66GV"
PART_TYPE"SMLF"
MATERIAL"IC"
SEC_TYPE""
CDS_LIB"pure_quanta"
PIN_NAMES_ROTATE"True"
CDS_LMAN_SYM_OUTLINE"-150,150,150,-150"
PART_NUMBER"AL001G66000";
"VCC"
$PN"5"35;
"E"
$PN"4"34;
"GND"
$PN"3"10;
"Z"
$PN"2"17;
"Y"
$PN"1"33;
%"UNIVERSAL_GND"
"1","(-8175,3800)","0","pure_quanta_power","I9";
;
CDS_LIB"pure_quanta_power"
HDL_POWER"GND";
"A"15;
END.
